# S9S_MB_2U (Grand Teton) — schematic netlist excerpt (pin names and nets, part order shuffled) for the footprints in the layout excerpt that follows; sources: Cadence DE-HDL packaged netlist, KiCad conversion of 03242023_DA0F0TMBIJ0_F0T_Motherboard_J_brd_V01_OCP.brd

R4414  Q_RES  33.2 1% CHIP  pkg 0402LF  page 123 : A = H_CPU1_MEMTRIP_VT_N ; B = H_CPU1_MEMTRIP_LVC1_N
C897  Q_CAP_DIFFBUS  DIFF BUS_0.22UF 6.3V 20% X6S  pkg C0201  page 174 : \1\ = P5E_CPU0_PE3_TX_C_DP<2> ; \2\ = P5E_CPU0_PE3_TX_DP<2>
PR4231  Q_RES  0 5% CHIP  pkg 0402LF  page 278 : A = NC_PVCCD_HV_CPU0_ACSP3 ; B = GND

(kicad_pcb
	(version 20260206)
	(generator "pcbnew")
	(generator_version "10.0")
	(general
		(thickness 1.6)
		(legacy_teardrops no)
	)
	(paper "A4")
	(title_block
		(title "03242023_DA0F0TMBIJ0_F0T_Motherboard_J_brd_V01_OCP.brd")
		(comment 1 "Grand Teton / footprints 462-464 of 6105")
	)
	(layers
		(0 "F.Cu" signal "TOP")
		(4 "In1.Cu" signal "GND")
		(6 "In2.Cu" signal "IN1")
		(8 "In3.Cu" signal "GND1")
		(10 "In4.Cu" signal "IN2")
		(12 "In5.Cu" signal "GND2")
		(14 "In6.Cu" signal "IN3")
		(16 "In7.Cu" signal "GND3")
		(18 "In8.Cu" signal "VCC")
		(20 "In9.Cu" signal "VCC1")
		(22 "In10.Cu" signal "GND4")
		(24 "In11.Cu" signal "IN4")
		(26 "In12.Cu" signal "GND5")
		(28 "In13.Cu" signal "IN5")
		(30 "In14.Cu" signal "GND6")
		(32 "In15.Cu" signal "IN6")
		(34 "In16.Cu" signal "GND7")
		(2 "B.Cu" signal "BOTTOM")
		(9 "F.Adhes" user "F.Adhesive")
		(11 "B.Adhes" user "B.Adhesive")
		(13 "F.Paste" user "Package Geometry/Pastemask Top")
		(15 "B.Paste" user "Package Geometry/Pastemask Bottom")
		(5 "F.SilkS" user "Ref Des/Silkscreen Top")
		(7 "B.SilkS" user "Ref Des/Silkscreen Bottom")
		(1 "F.Mask" user "Board Geometry/Soldermask Top")
		(3 "B.Mask" user "Board Geometry/Soldermask Bottom")
		(17 "Dwgs.User" user "User.Drawings")
		(19 "Cmts.User" user "User.Comments")
		(21 "Eco1.User" user "User.Eco1")
		(23 "Eco2.User" user "User.Eco2")
		(25 "Edge.Cuts" user "Board Geometry/Outline")
		(27 "Margin" user)
		(31 "F.CrtYd" user "Package Geometry/Place Bound Top")
		(29 "B.CrtYd" user "Package Geometry/Place Bound Bottom")
		(35 "F.Fab" user "Ref Des/Assembly Top")
		(33 "B.Fab" user "Ref Des/Assembly Bottom")
	)
	(footprint ""
		(layer "F.Cu")
		(at 413.48025 -408.517344 -90)
		(property "Reference" "C897"
			(at 0 0 270)
			(layer "F.SilkS")
			(hide yes)
			(effects
				(font
					(size 1.27 1.27)
				)
			)
		)
		(property "Value" ""
			(at 0 0 270)
			(layer "F.Fab")
			(effects
				(font
					(size 1.27 1.27)
				)
			)
		)
		(duplicate_pad_numbers_are_jumpers no)
		(fp_line
			(start -0.299974 0.150114)
			(end -0.299974 -0.150114)
			(stroke
				(width 0.1)
				(type default)
			)
			(layer "F.Fab")
		)
		(fp_line
			(start 0.299974 0.150114)
			(end -0.299974 0.150114)
			(stroke
				(width 0.1)
				(type default)
			)
			(layer "F.Fab")
		)
		(fp_line
			(start -0.299974 -0.150114)
			(end 0.299974 -0.150114)
			(stroke
				(width 0.1)
				(type default)
			)
			(layer "F.Fab")
		)
		(fp_line
			(start 0.299974 -0.150114)
			(end 0.299974 0.150114)
			(stroke
				(width 0.1)
				(type default)
			)
			(layer "F.Fab")
		)
		(pad "1" smd rect
			(at -0.2667 0 270)
			(size 0.3048 0.381)
			(layers "F.Cu" "F.Mask" "F.Paste")
			(net "P5E_CPU0_PE3_TX_C_DP<2>")
		)
		(pad "2" smd rect
			(at 0.2667 0 270)
			(size 0.3048 0.381)
			(layers "F.Cu" "F.Mask" "F.Paste")
			(net "P5E_CPU0_PE3_TX_DP<2>")
		)
	)
	(footprint ""
		(layer "F.Cu")
		(at 135.56488 -100.167948 -90)
		(property "Reference" "R4414"
			(at 0 0 270)
			(layer "F.SilkS")
			(hide yes)
			(effects
				(font
					(size 1.27 1.27)
				)
			)
		)
		(property "Value" ""
			(at 0 0 270)
			(layer "F.Fab")
			(effects
				(font
					(size 1.27 1.27)
				)
			)
		)
		(duplicate_pad_numbers_are_jumpers no)
		(fp_line
			(start -0.7874 0.4064)
			(end -0.7874 -0.4064)
			(stroke
				(width 0.1524)
				(type default)
			)
			(layer "F.SilkS")
		)
		(fp_line
			(start 0.7874 0.4064)
			(end -0.7874 0.4064)
			(stroke
				(width 0.1524)
				(type default)
			)
			(layer "F.SilkS")
		)
		(fp_line
			(start -0.7874 -0.4064)
			(end 0.7874 -0.4064)
			(stroke
				(width 0.1524)
				(type default)
			)
			(layer "F.SilkS")
		)
		(fp_line
			(start 0.7874 -0.4064)
			(end 0.7874 0.4064)
			(stroke
				(width 0.1524)
				(type default)
			)
			(layer "F.SilkS")
		)
		(fp_line
			(start -0.67945 0.3048)
			(end -0.67945 -0.305054)
			(stroke
				(width 0.1)
				(type default)
			)
			(layer "F.Fab")
		)
		(fp_line
			(start -0.12065 0.3048)
			(end -0.67945 0.3048)
			(stroke
				(width 0.1)
				(type default)
			)
			(layer "F.Fab")
		)
		(fp_line
			(start 0.120396 0.3048)
			(end 0.120396 0.2794)
			(stroke
				(width 0.1)
				(type default)
			)
			(layer "F.Fab")
		)
		(fp_line
			(start 0.67945 0.3048)
			(end 0.120396 0.3048)
			(stroke
				(width 0.1)
				(type default)
			)
			(layer "F.Fab")
		)
		(fp_line
			(start -0.12065 0.2794)
			(end -0.12065 0.3048)
			(stroke
				(width 0.1)
				(type default)
			)
			(layer "F.Fab")
		)
		(fp_line
			(start 0.120396 0.2794)
			(end -0.12065 0.2794)
			(stroke
				(width 0.1)
				(type default)
			)
			(layer "F.Fab")
		)
		(fp_line
			(start -0.12065 -0.2794)
			(end 0.12065 -0.2794)
			(stroke
				(width 0.1)
				(type default)
			)
			(layer "F.Fab")
		)
		(fp_line
			(start 0.12065 -0.2794)
			(end 0.12065 -0.3048)
			(stroke
				(width 0.1)
				(type default)
			)
			(layer "F.Fab")
		)
		(fp_line
			(start 0.12065 -0.3048)
			(end 0.67945 -0.3048)
			(stroke
				(width 0.1)
				(type default)
			)
			(layer "F.Fab")
		)
		(fp_line
			(start 0.67945 -0.3048)
			(end 0.67945 0.3048)
			(stroke
				(width 0.1)
				(type default)
			)
			(layer "F.Fab")
		)
		(fp_line
			(start -0.67945 -0.305054)
			(end -0.12065 -0.305054)
			(stroke
				(width 0.1)
				(type default)
			)
			(layer "F.Fab")
		)
		(fp_line
			(start -0.12065 -0.305054)
			(end -0.12065 -0.2794)
			(stroke
				(width 0.1)
				(type default)
			)
			(layer "F.Fab")
		)
		(pad "1" smd circle
			(at -0.40005 0 270)
			(size 0 0)
			(layers "F.Cu" "F.Mask" "F.Paste")
			(net "H_CPU1_MEMTRIP_VT_N")
		)
		(pad "2" smd circle
			(at 0.40005 0 270)
			(size 0 0)
			(layers "F.Cu" "F.Mask" "F.Paste")
			(net "H_CPU1_MEMTRIP_LVC1_N")
		)
	)
	(footprint ""
		(layer "F.Cu")
		(at 431.47488 -128.361948 90)
		(property "Reference" "PR4231"
			(at 0 0 90)
			(layer "F.SilkS")
			(hide yes)
			(effects
				(font
					(size 1.27 1.27)
				)
			)
		)
		(property "Value" ""
			(at 0 0 90)
			(layer "F.Fab")
			(effects
				(font
					(size 1.27 1.27)
				)
			)
		)
		(duplicate_pad_numbers_are_jumpers no)
		(fp_line
			(start 0.7874 -0.4064)
			(end 0.7874 0.4064)
			(stroke
				(width 0.1524)
				(type default)
			)
			(layer "F.SilkS")
		)
		(fp_line
			(start -0.7874 -0.4064)
			(end 0.7874 -0.4064)
			(stroke
				(width 0.1524)
				(type default)
			)
			(layer "F.SilkS")
		)
		(fp_line
			(start 0.7874 0.4064)
			(end -0.7874 0.4064)
			(stroke
				(width 0.1524)
				(type default)
			)
			(layer "F.SilkS")
		)
		(fp_line
			(start -0.7874 0.4064)
			(end -0.7874 -0.4064)
			(stroke
				(width 0.1524)
				(type default)
			)
			(layer "F.SilkS")
		)
		(fp_line
			(start -0.12065 -0.305054)
			(end -0.12065 -0.2794)
			(stroke
				(width 0.1)
				(type default)
			)
			(layer "F.Fab")
		)
		(fp_line
			(start -0.67945 -0.305054)
			(end -0.12065 -0.305054)
			(stroke
				(width 0.1)
				(type default)
			)
			(layer "F.Fab")
		)
		(fp_line
			(start 0.67945 -0.3048)
			(end 0.67945 0.3048)
			(stroke
				(width 0.1)
				(type default)
			)
			(layer "F.Fab")
		)
		(fp_line
			(start 0.12065 -0.3048)
			(end 0.67945 -0.3048)
			(stroke
				(width 0.1)
				(type default)
			)
			(layer "F.Fab")
		)
		(fp_line
			(start 0.12065 -0.2794)
			(end 0.12065 -0.3048)
			(stroke
				(width 0.1)
				(type default)
			)
			(layer "F.Fab")
		)
		(fp_line
			(start -0.12065 -0.2794)
			(end 0.12065 -0.2794)
			(stroke
				(width 0.1)
				(type default)
			)
			(layer "F.Fab")
		)
		(fp_line
			(start 0.120396 0.2794)
			(end -0.12065 0.2794)
			(stroke
				(width 0.1)
				(type default)
			)
			(layer "F.Fab")
		)
		(fp_line
			(start -0.12065 0.2794)
			(end -0.12065 0.3048)
			(stroke
				(width 0.1)
				(type default)
			)
			(layer "F.Fab")
		)
		(fp_line
			(start 0.67945 0.3048)
			(end 0.120396 0.3048)
			(stroke
				(width 0.1)
				(type default)
			)
			(layer "F.Fab")
		)
		(fp_line
			(start 0.120396 0.3048)
			(end 0.120396 0.2794)
			(stroke
				(width 0.1)
				(type default)
			)
			(layer "F.Fab")
		)
		(fp_line
			(start -0.12065 0.3048)
			(end -0.67945 0.3048)
			(stroke
				(width 0.1)
				(type default)
			)
			(layer "F.Fab")
		)
		(fp_line
			(start -0.67945 0.3048)
			(end -0.67945 -0.305054)
			(stroke
				(width 0.1)
				(type default)
			)
			(layer "F.Fab")
		)
		(pad "1" smd circle
			(at -0.40005 0 90)
			(size 0 0)
			(layers "F.Cu" "F.Mask" "F.Paste")
			(net "NC_PVCCD_HV_CPU0_ACSP3")
		)
		(pad "2" smd circle
			(at 0.40005 0 90)
			(size 0 0)
			(layers "F.Cu" "F.Mask" "F.Paste")
			(net "GND")
		)
	)
)
